# SCM (Grand Teton) — schematic netlist excerpt (pin names and nets, part order shuffled) for the footprints in the layout excerpt that follows; sources: Cadence DE-HDL packaged netlist, KiCad conversion of 12092022_DA0F0TMDCD0_F0T_Management_Board_D_brd_V3_OCP.brd

R733  Q_RES  0 5% CHIP  pkg 0402LF  page 50 : A = REAR_ID_RST_BTN_N ; B = FM_DEBUG_RST_BTN_N
R592  Q_RES  4.7K 1% CHIP  pkg 0402LF  page 25 : A = P3V3_AUX ; B = PU_J1_P1

(kicad_pcb
	(version 20260206)
	(generator "pcbnew")
	(generator_version "10.0")
	(general
		(thickness 1.6)
		(legacy_teardrops no)
	)
	(paper "A4")
	(title_block
		(title "12092022_DA0F0TMDCD0_F0T_Management_Board_D_brd_V3_OCP.brd")
		(comment 1 "Grand Teton / footprints 143-144 of 1440")
	)
	(layers
		(0 "F.Cu" signal "TOP")
		(4 "In1.Cu" signal "GND")
		(6 "In2.Cu" signal "IN1")
		(8 "In3.Cu" signal "GND1")
		(10 "In4.Cu" signal "IN2")
		(12 "In5.Cu" signal "VCC")
		(14 "In6.Cu" signal "VCC1")
		(16 "In7.Cu" signal "IN3")
		(18 "In8.Cu" signal "GND2")
		(20 "In9.Cu" signal "IN4")
		(22 "In10.Cu" signal "GND3")
		(2 "B.Cu" signal "BOTTOM")
		(9 "F.Adhes" user "F.Adhesive")
		(11 "B.Adhes" user "B.Adhesive")
		(13 "F.Paste" user "Package Geometry/Pastemask Top")
		(15 "B.Paste" user "Package Geometry/Pastemask Bottom")
		(5 "F.SilkS" user "Ref Des/Silkscreen Top")
		(7 "B.SilkS" user "Ref Des/Silkscreen Bottom")
		(1 "F.Mask" user "Board Geometry/Soldermask Top")
		(3 "B.Mask" user "Board Geometry/Soldermask Bottom")
		(17 "Dwgs.User" user "User.Drawings")
		(19 "Cmts.User" user "User.Comments")
		(21 "Eco1.User" user "User.Eco1")
		(23 "Eco2.User" user "User.Eco2")
		(25 "Edge.Cuts" user "Board Geometry/Outline")
		(27 "Margin" user)
		(31 "F.CrtYd" user "Package Geometry/Place Bound Top")
		(29 "B.CrtYd" user "Package Geometry/Place Bound Bottom")
		(35 "F.Fab" user "Ref Des/Assembly Top")
		(33 "B.Fab" user "Ref Des/Assembly Bottom")
	)
	(footprint ""
		(layer "F.Cu")
		(at 85.2932 -16.764)
		(property "Reference" "R733"
			(at 0 0 0)
			(layer "F.SilkS")
			(hide yes)
			(effects
				(font
					(size 1.27 1.27)
				)
			)
		)
		(property "Value" ""
			(at 0 0 0)
			(layer "F.Fab")
			(effects
				(font
					(size 1.27 1.27)
				)
			)
		)
		(duplicate_pad_numbers_are_jumpers no)
		(fp_line
			(start -0.7874 -0.4064)
			(end 0.7874 -0.4064)
			(stroke
				(width 0.1524)
				(type default)
			)
			(layer "F.SilkS")
		)
		(fp_line
			(start -0.7874 0.4064)
			(end -0.7874 -0.4064)
			(stroke
				(width 0.1524)
				(type default)
			)
			(layer "F.SilkS")
		)
		(fp_line
			(start 0.7874 -0.4064)
			(end 0.7874 0.4064)
			(stroke
				(width 0.1524)
				(type default)
			)
			(layer "F.SilkS")
		)
		(fp_line
			(start 0.7874 0.4064)
			(end -0.7874 0.4064)
			(stroke
				(width 0.1524)
				(type default)
			)
			(layer "F.SilkS")
		)
		(fp_line
			(start -0.67945 -0.305054)
			(end -0.12065 -0.305054)
			(stroke
				(width 0.1)
				(type default)
			)
			(layer "F.Fab")
		)
		(fp_line
			(start -0.67945 0.3048)
			(end -0.67945 -0.305054)
			(stroke
				(width 0.1)
				(type default)
			)
			(layer "F.Fab")
		)
		(fp_line
			(start -0.12065 -0.305054)
			(end -0.12065 -0.2794)
			(stroke
				(width 0.1)
				(type default)
			)
			(layer "F.Fab")
		)
		(fp_line
			(start -0.12065 -0.2794)
			(end 0.12065 -0.2794)
			(stroke
				(width 0.1)
				(type default)
			)
			(layer "F.Fab")
		)
		(fp_line
			(start -0.12065 0.2794)
			(end -0.12065 0.3048)
			(stroke
				(width 0.1)
				(type default)
			)
			(layer "F.Fab")
		)
		(fp_line
			(start -0.12065 0.3048)
			(end -0.67945 0.3048)
			(stroke
				(width 0.1)
				(type default)
			)
			(layer "F.Fab")
		)
		(fp_line
			(start 0.120396 0.2794)
			(end -0.12065 0.2794)
			(stroke
				(width 0.1)
				(type default)
			)
			(layer "F.Fab")
		)
		(fp_line
			(start 0.120396 0.3048)
			(end 0.120396 0.2794)
			(stroke
				(width 0.1)
				(type default)
			)
			(layer "F.Fab")
		)
		(fp_line
			(start 0.12065 -0.3048)
			(end 0.67945 -0.3048)
			(stroke
				(width 0.1)
				(type default)
			)
			(layer "F.Fab")
		)
		(fp_line
			(start 0.12065 -0.2794)
			(end 0.12065 -0.3048)
			(stroke
				(width 0.1)
				(type default)
			)
			(layer "F.Fab")
		)
		(fp_line
			(start 0.67945 -0.3048)
			(end 0.67945 0.3048)
			(stroke
				(width 0.1)
				(type default)
			)
			(layer "F.Fab")
		)
		(fp_line
			(start 0.67945 0.3048)
			(end 0.120396 0.3048)
			(stroke
				(width 0.1)
				(type default)
			)
			(layer "F.Fab")
		)
		(pad "1" smd circle
			(at -0.40005 0)
			(size 0 0)
			(layers "F.Cu" "F.Mask" "F.Paste")
			(net "REAR_ID_RST_BTN_N")
		)
		(pad "2" smd circle
			(at 0.40005 0)
			(size 0 0)
			(layers "F.Cu" "F.Mask" "F.Paste")
			(net "FM_DEBUG_RST_BTN_N")
		)
	)
	(footprint ""
		(layer "F.Cu")
		(at 47.752 -81.1276 90)
		(property "Reference" "R592"
			(at 0 0 90)
			(layer "F.SilkS")
			(hide yes)
			(effects
				(font
					(size 1.27 1.27)
				)
			)
		)
		(property "Value" ""
			(at 0 0 90)
			(layer "F.Fab")
			(effects
				(font
					(size 1.27 1.27)
				)
			)
		)
		(duplicate_pad_numbers_are_jumpers no)
		(fp_line
			(start 0.7874 -0.4064)
			(end 0.7874 0.4064)
			(stroke
				(width 0.1524)
				(type default)
			)
			(layer "F.SilkS")
		)
		(fp_line
			(start -0.7874 -0.4064)
			(end 0.7874 -0.4064)
			(stroke
				(width 0.1524)
				(type default)
			)
			(layer "F.SilkS")
		)
		(fp_line
			(start 0.7874 0.4064)
			(end -0.7874 0.4064)
			(stroke
				(width 0.1524)
				(type default)
			)
			(layer "F.SilkS")
		)
		(fp_line
			(start -0.7874 0.4064)
			(end -0.7874 -0.4064)
			(stroke
				(width 0.1524)
				(type default)
			)
			(layer "F.SilkS")
		)
		(fp_line
			(start -0.12065 -0.305054)
			(end -0.12065 -0.2794)
			(stroke
				(width 0.1)
				(type default)
			)
			(layer "F.Fab")
		)
		(fp_line
			(start -0.67945 -0.305054)
			(end -0.12065 -0.305054)
			(stroke
				(width 0.1)
				(type default)
			)
			(layer "F.Fab")
		)
		(fp_line
			(start 0.67945 -0.3048)
			(end 0.67945 0.3048)
			(stroke
				(width 0.1)
				(type default)
			)
			(layer "F.Fab")
		)
		(fp_line
			(start 0.12065 -0.3048)
			(end 0.67945 -0.3048)
			(stroke
				(width 0.1)
				(type default)
			)
			(layer "F.Fab")
		)
		(fp_line
			(start 0.12065 -0.2794)
			(end 0.12065 -0.3048)
			(stroke
				(width 0.1)
				(type default)
			)
			(layer "F.Fab")
		)
		(fp_line
			(start -0.12065 -0.2794)
			(end 0.12065 -0.2794)
			(stroke
				(width 0.1)
				(type default)
			)
			(layer "F.Fab")
		)
		(fp_line
			(start 0.120396 0.2794)
			(end -0.12065 0.2794)
			(stroke
				(width 0.1)
				(type default)
			)
			(layer "F.Fab")
		)
		(fp_line
			(start -0.12065 0.2794)
			(end -0.12065 0.3048)
			(stroke
				(width 0.1)
				(type default)
			)
			(layer "F.Fab")
		)
		(fp_line
			(start 0.67945 0.3048)
			(end 0.120396 0.3048)
			(stroke
				(width 0.1)
				(type default)
			)
			(layer "F.Fab")
		)
		(fp_line
			(start 0.120396 0.3048)
			(end 0.120396 0.2794)
			(stroke
				(width 0.1)
				(type default)
			)
			(layer "F.Fab")
		)
		(fp_line
			(start -0.12065 0.3048)
			(end -0.67945 0.3048)
			(stroke
				(width 0.1)
				(type default)
			)
			(layer "F.Fab")
		)
		(fp_line
			(start -0.67945 0.3048)
			(end -0.67945 -0.305054)
			(stroke
				(width 0.1)
				(type default)
			)
			(layer "F.Fab")
		)
		(pad "1" smd circle
			(at -0.40005 0 90)
			(size 0 0)
			(layers "F.Cu" "F.Mask" "F.Paste")
			(net "P3V3_AUX")
		)
		(pad "2" smd circle
			(at 0.40005 0 90)
			(size 0 0)
			(layers "F.Cu" "F.Mask" "F.Paste")
			(net "PU_J1_P1")
		)
	)
)
